# T6G (Grand Teton) — schematic netlist excerpt (pin names and nets, part order shuffled) for the footprints in the layout excerpt that follows; sources: Cadence DE-HDL packaged netlist, KiCad conversion of 04192023_DAF0TMB3IC0_F0TG_MB_C_brd_V02_OCP.brd

PC557_4  Q_CAP  22UF 16V 20% X6S  pkg C0805  page 195 : A = SW_P12V_AUX_PVDDCR_CPU0_P0_FLT ; B = GND
C141  Q_CAP  0.1UF 10V 10% X7S  pkg C0201  page 323 : A = P0V9_CPU1_RT0_2A ; B = GND
R3513  Q_RES  54.9K 1% CHIP  pkg 0402LF  page 127 : A = FM_GPU_PWRGD ; B = GND
C377  Q_CAP  0.1UF 10V 10% X7S  pkg C0201  page 345 : A = P1V8_CPU1_RT2_1A ; B = GND

(kicad_pcb
	(version 20260206)
	(generator "pcbnew")
	(generator_version "10.0")
	(general
		(thickness 1.6)
		(legacy_teardrops no)
	)
	(paper "A4")
	(title_block
		(title "04192023_DAF0TMB3IC0_F0TG_MB_C_brd_V02_OCP.brd")
		(comment 1 "Grand Teton / footprints 6681-6684 of 8354")
	)
	(layers
		(0 "F.Cu" signal "TOP")
		(4 "In1.Cu" signal "GND")
		(6 "In2.Cu" signal "IN1")
		(8 "In3.Cu" signal "GND1")
		(10 "In4.Cu" signal "IN2")
		(12 "In5.Cu" signal "GND2")
		(14 "In6.Cu" signal "IN3")
		(16 "In7.Cu" signal "GND3")
		(18 "In8.Cu" signal "VCC")
		(20 "In9.Cu" signal "VCC1")
		(22 "In10.Cu" signal "GND4")
		(24 "In11.Cu" signal "IN4")
		(26 "In12.Cu" signal "GND5")
		(28 "In13.Cu" signal "IN5")
		(30 "In14.Cu" signal "GND6")
		(32 "In15.Cu" signal "IN6")
		(34 "In16.Cu" signal "GND7")
		(2 "B.Cu" signal "BOTTOM")
		(9 "F.Adhes" user "F.Adhesive")
		(11 "B.Adhes" user "B.Adhesive")
		(13 "F.Paste" user "Package Geometry/Pastemask Top")
		(15 "B.Paste" user "Package Geometry/Pastemask Bottom")
		(5 "F.SilkS" user "Ref Des/Silkscreen Top")
		(7 "B.SilkS" user "Ref Des/Silkscreen Bottom")
		(1 "F.Mask" user "Board Geometry/Soldermask Top")
		(3 "B.Mask" user "Board Geometry/Soldermask Bottom")
		(17 "Dwgs.User" user "User.Drawings")
		(19 "Cmts.User" user "User.Comments")
		(21 "Eco1.User" user "User.Eco1")
		(23 "Eco2.User" user "User.Eco2")
		(25 "Edge.Cuts" user "Board Geometry/Outline")
		(27 "Margin" user)
		(31 "F.CrtYd" user "Package Geometry/Place Bound Top")
		(29 "B.CrtYd" user "Package Geometry/Place Bound Bottom")
		(35 "F.Fab" user "Ref Des/Assembly Top")
		(33 "B.Fab" user "Ref Des/Assembly Bottom")
	)
	(footprint ""
		(layer "B.Cu")
		(at 51.72964 -426.003212 -90)
		(property "Reference" "R3513"
			(at 0 0 90)
			(layer "B.SilkS")
			(hide yes)
			(effects
				(font
					(size 1.27 1.27)
				)
				(justify mirror)
			)
		)
		(property "Value" ""
			(at 0 0 90)
			(layer "B.Fab")
			(effects
				(font
					(size 1.27 1.27)
				)
				(justify mirror)
			)
		)
		(duplicate_pad_numbers_are_jumpers no)
		(fp_line
			(start -0.7874 0.4064)
			(end 0.7874 0.4064)
			(stroke
				(width 0.1524)
				(type default)
			)
			(layer "B.SilkS")
		)
		(fp_line
			(start 0.7874 0.4064)
			(end 0.7874 -0.4064)
			(stroke
				(width 0.1524)
				(type default)
			)
			(layer "B.SilkS")
		)
		(fp_line
			(start -0.7874 -0.4064)
			(end -0.7874 0.4064)
			(stroke
				(width 0.1524)
				(type default)
			)
			(layer "B.SilkS")
		)
		(fp_line
			(start 0.7874 -0.4064)
			(end -0.7874 -0.4064)
			(stroke
				(width 0.1524)
				(type default)
			)
			(layer "B.SilkS")
		)
		(fp_line
			(start -0.67945 0.3048)
			(end -0.120396 0.3048)
			(stroke
				(width 0.1)
				(type default)
			)
			(layer "B.Fab")
		)
		(fp_line
			(start -0.120396 0.3048)
			(end -0.120396 0.2794)
			(stroke
				(width 0.1)
				(type default)
			)
			(layer "B.Fab")
		)
		(fp_line
			(start 0.12065 0.3048)
			(end 0.67945 0.3048)
			(stroke
				(width 0.1)
				(type default)
			)
			(layer "B.Fab")
		)
		(fp_line
			(start 0.67945 0.3048)
			(end 0.67945 -0.305054)
			(stroke
				(width 0.1)
				(type default)
			)
			(layer "B.Fab")
		)
		(fp_line
			(start -0.120396 0.2794)
			(end 0.12065 0.2794)
			(stroke
				(width 0.1)
				(type default)
			)
			(layer "B.Fab")
		)
		(fp_line
			(start 0.12065 0.2794)
			(end 0.12065 0.3048)
			(stroke
				(width 0.1)
				(type default)
			)
			(layer "B.Fab")
		)
		(fp_line
			(start -0.12065 -0.2794)
			(end -0.12065 -0.3048)
			(stroke
				(width 0.1)
				(type default)
			)
			(layer "B.Fab")
		)
		(fp_line
			(start 0.12065 -0.2794)
			(end -0.12065 -0.2794)
			(stroke
				(width 0.1)
				(type default)
			)
			(layer "B.Fab")
		)
		(fp_line
			(start -0.67945 -0.3048)
			(end -0.67945 0.3048)
			(stroke
				(width 0.1)
				(type default)
			)
			(layer "B.Fab")
		)
		(fp_line
			(start -0.12065 -0.3048)
			(end -0.67945 -0.3048)
			(stroke
				(width 0.1)
				(type default)
			)
			(layer "B.Fab")
		)
		(fp_line
			(start 0.12065 -0.305054)
			(end 0.12065 -0.2794)
			(stroke
				(width 0.1)
				(type default)
			)
			(layer "B.Fab")
		)
		(fp_line
			(start 0.67945 -0.305054)
			(end 0.12065 -0.305054)
			(stroke
				(width 0.1)
				(type default)
			)
			(layer "B.Fab")
		)
		(pad "1" smd circle
			(at 0.40005 0 90)
			(size 0 0)
			(layers "B.Cu" "B.Mask" "B.Paste")
			(net "FM_GPU_PWRGD")
		)
		(pad "2" smd circle
			(at -0.40005 0 90)
			(size 0 0)
			(layers "B.Cu" "B.Mask" "B.Paste")
			(net "GND")
		)
	)
	(footprint ""
		(layer "B.Cu")
		(at 48.71847 -388.011162 -90)
		(property "Reference" "C141"
			(at 0 0 90)
			(layer "B.SilkS")
			(hide yes)
			(effects
				(font
					(size 1.27 1.27)
				)
				(justify mirror)
			)
		)
		(property "Value" ""
			(at 0 0 90)
			(layer "B.Fab")
			(effects
				(font
					(size 1.27 1.27)
				)
				(justify mirror)
			)
		)
		(duplicate_pad_numbers_are_jumpers no)
		(fp_line
			(start -0.299974 0.150114)
			(end 0.299974 0.150114)
			(stroke
				(width 0.1)
				(type default)
			)
			(layer "B.Fab")
		)
		(fp_line
			(start 0.299974 0.150114)
			(end 0.299974 -0.150114)
			(stroke
				(width 0.1)
				(type default)
			)
			(layer "B.Fab")
		)
		(fp_line
			(start -0.299974 -0.150114)
			(end -0.299974 0.150114)
			(stroke
				(width 0.1)
				(type default)
			)
			(layer "B.Fab")
		)
		(fp_line
			(start 0.299974 -0.150114)
			(end -0.299974 -0.150114)
			(stroke
				(width 0.1)
				(type default)
			)
			(layer "B.Fab")
		)
		(pad "1" smd rect
			(at 0.2667 0 90)
			(size 0.3048 0.381)
			(layers "B.Cu" "B.Mask" "B.Paste")
			(net "P0V9_CPU1_RT0_2A")
		)
		(pad "2" smd rect
			(at -0.2667 0 90)
			(size 0.3048 0.381)
			(layers "B.Cu" "B.Mask" "B.Paste")
			(net "GND")
		)
	)
	(footprint ""
		(layer "B.Cu")
		(at 388.382256 -182.867554 -90)
		(property "Reference" "PC557_4"
			(at 0 0 90)
			(layer "B.SilkS")
			(hide yes)
			(effects
				(font
					(size 1.27 1.27)
				)
				(justify mirror)
			)
		)
		(property "Value" ""
			(at 0 0 90)
			(layer "B.Fab")
			(effects
				(font
					(size 1.27 1.27)
				)
				(justify mirror)
			)
		)
		(duplicate_pad_numbers_are_jumpers no)
		(fp_line
			(start -1.524 0.762)
			(end 1.524 0.762)
			(stroke
				(width 0.1524)
				(type default)
			)
			(layer "B.SilkS")
		)
		(fp_line
			(start 1.524 0.762)
			(end 1.524 -0.762)
			(stroke
				(width 0.1524)
				(type default)
			)
			(layer "B.SilkS")
		)
		(fp_line
			(start -1.524 -0.762)
			(end -1.524 0.762)
			(stroke
				(width 0.1524)
				(type default)
			)
			(layer "B.SilkS")
		)
		(fp_line
			(start 1.524 -0.762)
			(end -1.524 -0.762)
			(stroke
				(width 0.1524)
				(type default)
			)
			(layer "B.SilkS")
		)
		(fp_line
			(start -1.1049 0.724916)
			(end -1.1049 -0.724916)
			(stroke
				(width 0.1)
				(type default)
			)
			(layer "B.Fab")
		)
		(fp_line
			(start 1.1049 0.724916)
			(end -1.1049 0.724916)
			(stroke
				(width 0.1)
				(type default)
			)
			(layer "B.Fab")
		)
		(fp_line
			(start -1.1049 -0.724916)
			(end 1.1049 -0.724916)
			(stroke
				(width 0.1)
				(type default)
			)
			(layer "B.Fab")
		)
		(fp_line
			(start 1.1049 -0.724916)
			(end 1.1049 0.724916)
			(stroke
				(width 0.1)
				(type default)
			)
			(layer "B.Fab")
		)
		(pad "1" smd rect
			(at 0.889 0 270)
			(size 1.016 1.27)
			(layers "B.Cu" "B.Mask" "B.Paste")
			(net "SW_P12V_AUX_PVDDCR_CPU0_P0_FLT")
		)
		(pad "2" smd rect
			(at -0.889 0 270)
			(size 1.016 1.27)
			(layers "B.Cu" "B.Mask" "B.Paste")
			(net "GND")
		)
	)
	(footprint ""
		(layer "B.Cu")
		(at 155.406344 -386.766562 90)
		(property "Reference" "C377"
			(at 0 0 90)
			(layer "B.SilkS")
			(hide yes)
			(effects
				(font
					(size 1.27 1.27)
				)
				(justify mirror)
			)
		)
		(property "Value" ""
			(at 0 0 90)
			(layer "B.Fab")
			(effects
				(font
					(size 1.27 1.27)
				)
				(justify mirror)
			)
		)
		(duplicate_pad_numbers_are_jumpers no)
		(fp_line
			(start 0.299974 -0.150114)
			(end -0.299974 -0.150114)
			(stroke
				(width 0.1)
				(type default)
			)
			(layer "B.Fab")
		)
		(fp_line
			(start -0.299974 -0.150114)
			(end -0.299974 0.150114)
			(stroke
				(width 0.1)
				(type default)
			)
			(layer "B.Fab")
		)
		(fp_line
			(start 0.299974 0.150114)
			(end 0.299974 -0.150114)
			(stroke
				(width 0.1)
				(type default)
			)
			(layer "B.Fab")
		)
		(fp_line
			(start -0.299974 0.150114)
			(end 0.299974 0.150114)
			(stroke
				(width 0.1)
				(type default)
			)
			(layer "B.Fab")
		)
		(pad "1" smd rect
			(at 0.2667 0 270)
			(size 0.3048 0.381)
			(layers "B.Cu" "B.Mask" "B.Paste")
			(net "P1V8_CPU1_RT2_1A")
		)
		(pad "2" smd rect
			(at -0.2667 0 270)
			(size 0.3048 0.381)
			(layers "B.Cu" "B.Mask" "B.Paste")
			(net "GND")
		)
	)
)
